(kicad_pcb
	(version 20260206)
	(generator "pcbnew")
	(generator_version "10.0")
	(general
		(thickness 1.6)
		(legacy_teardrops no)
	)
	(paper "A4")
	(title_block
		(title "Bryce Canyon_F.DPB_16315-1-OCP.brd")
		(comment 1 "Bryce Canyon / footprints 1232-1238 of 2223")
	)
	(layers
		(0 "F.Cu" signal "TOP")
		(4 "In1.Cu" signal "L2GND")
		(6 "In2.Cu" signal "L3")
		(8 "In3.Cu" signal "L4GND")
		(10 "In4.Cu" signal "L5")
		(12 "In5.Cu" signal "L6VCC")
		(14 "In6.Cu" signal "L7VCC")
		(16 "In7.Cu" signal "L8")
		(18 "In8.Cu" signal "L9GND")
		(20 "In9.Cu" signal "L10")
		(22 "In10.Cu" signal "L11GND")
		(2 "B.Cu" signal "BOTTOM")
		(9 "F.Adhes" user "F.Adhesive")
		(11 "B.Adhes" user "B.Adhesive")
		(13 "F.Paste" user "Package Geometry/Pastemask Top")
		(15 "B.Paste" user "Package Geometry/Pastemask Bottom")
		(5 "F.SilkS" user "Ref Des/Silkscreen Top")
		(7 "B.SilkS" user "Ref Des/Silkscreen Bottom")
		(1 "F.Mask" user "Board Geometry/Soldermask Top")
		(3 "B.Mask" user "Board Geometry/Soldermask Bottom")
		(17 "Dwgs.User" user "User.Drawings")
		(19 "Cmts.User" user "User.Comments")
		(21 "Eco1.User" user "User.Eco1")
		(23 "Eco2.User" user "User.Eco2")
		(25 "Edge.Cuts" user "Board Geometry/Outline")
		(27 "Margin" user)
		(31 "F.CrtYd" user "Package Geometry/Place Bound Top")
		(29 "B.CrtYd" user "Package Geometry/Place Bound Bottom")
		(35 "F.Fab" user "Ref Des/Assembly Top")
		(33 "B.Fab" user "Ref Des/Assembly Bottom")
	)
	(footprint ""
		(layer "F.Cu")
		(at 384.734562 -273.660616 -90)
		(property "Reference" "C143"
			(at 0 0 270)
			(layer "F.SilkS")
			(hide yes)
			(effects
				(font
					(size 1.27 1.27)
				)
			)
		)
		(property "Value" "SCD01U16V1KX-GP"
			(at -2.8321 -1.7399 270)
			(unlocked yes)
			(layer "F.Fab")
			(hide yes)
			(effects
				(font
					(size 1.016 1.016)
					(thickness 0.1524)
				)
			)
		)
		(property "Device Type" "C0201H13"
			(at -2.8321 -3.2639 270)
			(unlocked yes)
			(layer "F.Fab")
			(hide yes)
			(effects
				(font
					(size 1.016 1.016)
					(thickness 0.1524)
				)
			)
		)
		(duplicate_pad_numbers_are_jumpers no)
		(fp_rect
			(start -0.2794 0.6477)
			(end 0.2794 -0.6477)
			(stroke
				(width 0)
				(type default)
			)
			(fill no)
			(layer "F.CrtYd")
		)
		(fp_rect
			(start -0.2794 0.6477)
			(end 0.2794 -0.6477)
			(stroke
				(width 0)
				(type default)
			)
			(fill no)
			(layer "F.Fab")
		)
		(pad "1" smd custom
			(at 0 -0.2794 270)
			(size 0.0762 0.0762)
			(layers "F.Cu" "F.Mask" "F.Paste")
			(net "SAS_HDD_RX_P8")
			(options
				(clearance outline)
				(anchor circle)
			)
			(primitives
				(gr_poly
					(pts
						(arc
							(start 0.1524 -0.127)
							(mid 0.137521 -0.162921)
							(end 0.1016 -0.1778)
						)
						(arc
							(start -0.1016 -0.1778)
							(mid -0.137521 -0.162921)
							(end -0.1524 -0.127)
						)
						(arc
							(start -0.1524 0.127)
							(mid -0.137521 0.162921)
							(end -0.1016 0.1778)
						)
						(arc
							(start 0.1016 0.1778)
							(mid 0.137521 0.162921)
							(end 0.1524 0.127)
						)
					)
					(width 0)
					(fill yes)
				)
			)
		)
		(pad "2" smd custom
			(at 0 0.2794 270)
			(size 0.0762 0.0762)
			(layers "F.Cu" "F.Mask" "F.Paste")
			(net "PHY_SCC_A_TO_DRV_A_8_DP")
			(options
				(clearance outline)
				(anchor circle)
			)
			(primitives
				(gr_poly
					(pts
						(arc
							(start 0.1524 -0.127)
							(mid 0.137521 -0.162921)
							(end 0.1016 -0.1778)
						)
						(arc
							(start -0.1016 -0.1778)
							(mid -0.137521 -0.162921)
							(end -0.1524 -0.127)
						)
						(arc
							(start -0.1524 0.127)
							(mid -0.137521 0.162921)
							(end -0.1016 0.1778)
						)
						(arc
							(start 0.1016 0.1778)
							(mid 0.137521 0.162921)
							(end 0.1524 0.127)
						)
					)
					(width 0)
					(fill yes)
				)
			)
		)
	)
	(footprint ""
		(layer "F.Cu")
		(at 377.246134 -287.170114)
		(property "Reference" "Q295"
			(at 0 0 0)
			(layer "F.SilkS")
			(hide yes)
			(effects
				(font
					(size 1.27 1.27)
				)
			)
		)
		(property "Value" "SSM3K324R-GP"
			(at 0.127 -8.9662 0)
			(unlocked yes)
			(layer "F.Fab")
			(hide yes)
			(effects
				(font
					(size 1.016 1.016)
					(thickness 0.1524)
				)
			)
		)
		(property "Device Type" "SOT23DGS2D4H35"
			(at 0.127 -10.4902 0)
			(unlocked yes)
			(layer "F.Fab")
			(hide yes)
			(effects
				(font
					(size 1.016 1.016)
					(thickness 0.1524)
				)
			)
		)
		(duplicate_pad_numbers_are_jumpers no)
		(fp_line
			(start -1.651 -1.778)
			(end -1.651 1.778)
			(stroke
				(width 0.1524)
				(type default)
			)
			(layer "F.SilkS")
		)
		(fp_line
			(start -1.651 1.778)
			(end 1.651 1.778)
			(stroke
				(width 0.1524)
				(type default)
			)
			(layer "F.SilkS")
		)
		(fp_line
			(start 1.651 -1.778)
			(end -1.651 -1.778)
			(stroke
				(width 0.1524)
				(type default)
			)
			(layer "F.SilkS")
		)
		(fp_line
			(start 1.651 1.778)
			(end 1.651 -1.778)
			(stroke
				(width 0.1524)
				(type default)
			)
			(layer "F.SilkS")
		)
		(fp_poly
			(pts
				(xy -1.778 1.8796) (xy -1.778 -1.8796) (xy 1.778 -1.8796) (xy 1.778 1.8796)
			)
			(stroke
				(width 0)
				(type default)
			)
			(fill no)
			(layer "F.CrtYd")
		)
		(fp_poly
			(pts
				(xy -1.778 1.8796) (xy -1.778 -1.8796) (xy 1.778 -1.8796) (xy 1.778 1.8796)
			)
			(stroke
				(width 0)
				(type default)
			)
			(fill no)
			(layer "F.Fab")
		)
		(pad "D" smd custom
			(at 0 -0.9525)
			(size 0.1905 0.1905)
			(layers "F.Cu" "F.Mask" "F.Paste")
			(net "DRV_ACT_32_N")
			(options
				(clearance outline)
				(anchor circle)
			)
			(primitives
				(gr_poly
					(pts
						(arc
							(start -0.1778 0.5715)
							(mid -0.321484 0.511984)
							(end -0.381 0.3683)
						)
						(arc
							(start -0.381 -0.3683)
							(mid -0.321484 -0.511984)
							(end -0.1778 -0.5715)
						)
						(arc
							(start 0.1778 -0.5715)
							(mid 0.321484 -0.511984)
							(end 0.381 -0.3683)
						)
						(arc
							(start 0.381 0.3683)
							(mid 0.321484 0.511984)
							(end 0.1778 0.5715)
						)
					)
					(width 0)
					(fill yes)
				)
			)
		)
		(pad "G" smd custom
			(at -0.98425 0.9525)
			(size 0.1905 0.1905)
			(layers "F.Cu" "F.Mask" "F.Paste")
			(net "DRIVE_B_32_ACT")
			(options
				(clearance outline)
				(anchor circle)
			)
			(primitives
				(gr_poly
					(pts
						(arc
							(start -0.1778 0.5715)
							(mid -0.321484 0.511984)
							(end -0.381 0.3683)
						)
						(arc
							(start -0.381 -0.3683)
							(mid -0.321484 -0.511984)
							(end -0.1778 -0.5715)
						)
						(arc
							(start 0.1778 -0.5715)
							(mid 0.321484 -0.511984)
							(end 0.381 -0.3683)
						)
						(arc
							(start 0.381 0.3683)
							(mid 0.321484 0.511984)
							(end 0.1778 0.5715)
						)
					)
					(width 0)
					(fill yes)
				)
			)
		)
		(pad "S" smd custom
			(at 0.98425 0.9525)
			(size 0.1905 0.1905)
			(layers "F.Cu" "F.Mask" "F.Paste")
			(net "GND")
			(options
				(clearance outline)
				(anchor circle)
			)
			(primitives
				(gr_poly
					(pts
						(arc
							(start -0.1778 0.5715)
							(mid -0.321484 0.511984)
							(end -0.381 0.3683)
						)
						(arc
							(start -0.381 -0.3683)
							(mid -0.321484 -0.511984)
							(end -0.1778 -0.5715)
						)
						(arc
							(start 0.1778 -0.5715)
							(mid 0.321484 -0.511984)
							(end 0.381 -0.3683)
						)
						(arc
							(start 0.381 0.3683)
							(mid 0.321484 0.511984)
							(end 0.1778 0.5715)
						)
					)
					(width 0)
					(fill yes)
				)
			)
		)
	)
	(footprint ""
		(layer "F.Cu")
		(at 447.834512 -44.219368 -90)
		(property "Reference" "C480"
			(at 0 0 270)
			(layer "F.SilkS")
			(hide yes)
			(effects
				(font
					(size 1.27 1.27)
				)
			)
		)
		(property "Value" "SCD01U16V1KX-GP"
			(at -2.8321 -1.7399 270)
			(unlocked yes)
			(layer "F.Fab")
			(hide yes)
			(effects
				(font
					(size 1.016 1.016)
					(thickness 0.1524)
				)
			)
		)
		(property "Device Type" "C0201H13"
			(at -2.8321 -3.2639 270)
			(unlocked yes)
			(layer "F.Fab")
			(hide yes)
			(effects
				(font
					(size 1.016 1.016)
					(thickness 0.1524)
				)
			)
		)
		(duplicate_pad_numbers_are_jumpers no)
		(fp_rect
			(start -0.2794 0.6477)
			(end 0.2794 -0.6477)
			(stroke
				(width 0)
				(type default)
			)
			(fill no)
			(layer "F.CrtYd")
		)
		(fp_rect
			(start -0.2794 0.6477)
			(end 0.2794 -0.6477)
			(stroke
				(width 0)
				(type default)
			)
			(fill no)
			(layer "F.Fab")
		)
		(pad "1" smd custom
			(at 0 -0.2794 270)
			(size 0.0762 0.0762)
			(layers "F.Cu" "F.Mask" "F.Paste")
			(net "SAS_HDD_RX_N34")
			(options
				(clearance outline)
				(anchor circle)
			)
			(primitives
				(gr_poly
					(pts
						(arc
							(start 0.1524 -0.127)
							(mid 0.137521 -0.162921)
							(end 0.1016 -0.1778)
						)
						(arc
							(start -0.1016 -0.1778)
							(mid -0.137521 -0.162921)
							(end -0.1524 -0.127)
						)
						(arc
							(start -0.1524 0.127)
							(mid -0.137521 0.162921)
							(end -0.1016 0.1778)
						)
						(arc
							(start 0.1016 0.1778)
							(mid 0.137521 0.162921)
							(end 0.1524 0.127)
						)
					)
					(width 0)
					(fill yes)
				)
			)
		)
		(pad "2" smd custom
			(at 0 0.2794 270)
			(size 0.0762 0.0762)
			(layers "F.Cu" "F.Mask" "F.Paste")
			(net "PHY_SCC_A_TO_DRV_A_34_DN")
			(options
				(clearance outline)
				(anchor circle)
			)
			(primitives
				(gr_poly
					(pts
						(arc
							(start 0.1524 -0.127)
							(mid 0.137521 -0.162921)
							(end 0.1016 -0.1778)
						)
						(arc
							(start -0.1016 -0.1778)
							(mid -0.137521 -0.162921)
							(end -0.1524 -0.127)
						)
						(arc
							(start -0.1524 0.127)
							(mid -0.137521 0.162921)
							(end -0.1016 0.1778)
						)
						(arc
							(start 0.1016 0.1778)
							(mid 0.137521 0.162921)
							(end 0.1524 0.127)
						)
					)
					(width 0)
					(fill yes)
				)
			)
		)
	)
	(footprint ""
		(layer "F.Cu")
		(at 396.60195 -73.954894 180)
		(property "Reference" "C462"
			(at 0 0 180)
			(layer "F.SilkS")
			(hide yes)
			(effects
				(font
					(size 1.27 1.27)
				)
			)
		)
		(property "Value" "SC4D7U25V5KX-1-GP"
			(at -0.0762 -6.1214 180)
			(unlocked yes)
			(layer "F.Fab")
			(hide yes)
			(effects
				(font
					(size 1.016 1.016)
					(thickness 0.1524)
				)
			)
		)
		(property "Device Type" "C805H58"
			(at -0.0762 -8.1534 180)
			(unlocked yes)
			(layer "F.Fab")
			(hide yes)
			(effects
				(font
					(size 1.016 1.016)
					(thickness 0.1524)
				)
			)
		)
		(duplicate_pad_numbers_are_jumpers no)
		(fp_line
			(start 0.635 0)
			(end -0.635 0)
			(stroke
				(width 0.508)
				(type default)
			)
			(layer "F.SilkS")
		)
		(fp_rect
			(start -0.9652 1.778)
			(end 0.9652 -1.778)
			(stroke
				(width 0)
				(type default)
			)
			(fill no)
			(layer "F.CrtYd")
		)
		(fp_poly
			(pts
				(xy -0.9652 -1.778) (xy 0.9652 -1.778) (xy 0.9652 1.778) (xy -0.9652 1.778)
			)
			(stroke
				(width 0)
				(type default)
			)
			(fill no)
			(layer "F.Fab")
		)
		(pad "1" smd rect
			(at 0 -0.9652 180)
			(size 1.397 1.143)
			(layers "F.Cu" "F.Mask" "F.Paste")
			(net "P12V_HDD32")
		)
		(pad "2" smd rect
			(at 0 0.9652 180)
			(size 1.397 1.143)
			(layers "F.Cu" "F.Mask" "F.Paste")
			(net "GND")
		)
	)
	(footprint ""
		(layer "F.Cu")
		(at 315.149992 -324.39991)
		(property "Reference" "RLED31"
			(at 0 0 0)
			(layer "F.SilkS")
			(hide yes)
			(effects
				(font
					(size 1.27 1.27)
				)
			)
		)
		(property "Value" "LED-BY-19-GP"
			(at -2.132076 1.414018 0)
			(unlocked yes)
			(layer "F.Fab")
			(hide yes)
			(effects
				(font
					(size 1.016 1.016)
					(thickness 0.1524)
				)
			)
		)
		(property "Device Type" "LED-1615-4PH26"
			(at -2.132076 -0.109982 0)
			(unlocked yes)
			(layer "F.Fab")
			(hide yes)
			(effects
				(font
					(size 1.016 1.016)
					(thickness 0.1524)
				)
			)
		)
		(duplicate_pad_numbers_are_jumpers no)
		(fp_line
			(start -1.2954 0.254)
			(end -1.2954 1.6002)
			(stroke
				(width 0.508)
				(type default)
			)
			(layer "F.SilkS")
		)
		(fp_line
			(start -1.2954 1.6002)
			(end 1.2954 1.6002)
			(stroke
				(width 0.508)
				(type default)
			)
			(layer "F.SilkS")
		)
		(fp_line
			(start -1.1176 -1.4224)
			(end 1.1176 -1.4224)
			(stroke
				(width 0.1524)
				(type default)
			)
			(layer "F.SilkS")
		)
		(fp_line
			(start -1.1176 1.4224)
			(end -1.1176 -1.4224)
			(stroke
				(width 0.1524)
				(type default)
			)
			(layer "F.SilkS")
		)
		(fp_line
			(start 1.1176 -1.4224)
			(end 1.1176 1.4224)
			(stroke
				(width 0.1524)
				(type default)
			)
			(layer "F.SilkS")
		)
		(fp_line
			(start 1.1176 1.4224)
			(end -1.1176 1.4224)
			(stroke
				(width 0.1524)
				(type default)
			)
			(layer "F.SilkS")
		)
		(fp_line
			(start 1.2954 1.6002)
			(end 1.2954 0.254)
			(stroke
				(width 0.508)
				(type default)
			)
			(layer "F.SilkS")
		)
		(fp_rect
			(start -0.7493 0.8001)
			(end 0.7493 -0.8001)
			(stroke
				(width 0)
				(type default)
			)
			(fill no)
			(layer "F.CrtYd")
		)
		(fp_poly
			(pts
				(xy -1.3716 1.6764) (xy -1.3716 -1.6764) (xy 1.3716 -1.6764) (xy 1.3716 0.0635) (xy 0.7493 0.0635)
				(xy 0.7493 -0.8001) (xy -0.7493 -0.8001) (xy -0.7493 0.8001) (xy 0.7493 0.8001) (xy 0.7493 0.0762)
				(xy 1.3716 0.0762) (xy 1.3716 1.6764)
			)
			(stroke
				(width 0)
				(type default)
			)
			(fill no)
			(layer "F.CrtYd")
		)
		(fp_rect
			(start -1.3716 1.6764)
			(end 1.3716 -1.6764)
			(stroke
				(width 0)
				(type default)
			)
			(fill no)
			(layer "F.Fab")
		)
		(pad "1" smd rect
			(at 0.50038 -0.73025)
			(size 0.7112 0.8636)
			(layers "F.Cu" "F.Mask" "F.Paste")
			(net "DRV_ACT_30")
		)
		(pad "2" smd rect
			(at -0.50038 -0.73025)
			(size 0.7112 0.8636)
			(layers "F.Cu" "F.Mask" "F.Paste")
			(net "FLT_HDD30")
		)
		(pad "3" smd rect
			(at 0.50038 0.73025)
			(size 0.7112 0.8636)
			(layers "F.Cu" "F.Mask" "F.Paste")
			(net "DRV_ACT_30_N")
		)
		(pad "4" smd rect
			(at -0.50038 0.73025)
			(size 0.7112 0.8636)
			(layers "F.Cu" "F.Mask" "F.Paste")
			(net "FLT_HDD30_N")
		)
	)
	(footprint ""
		(layer "F.Cu")
		(at 157.748732 -137.34923)
		(property "Reference" "C545"
			(at 0 0 0)
			(layer "F.SilkS")
			(hide yes)
			(effects
				(font
					(size 1.27 1.27)
				)
			)
		)
		(property "Value" "SCD015U25V2KX-GP"
			(at 1.1811 -2.7051 0)
			(unlocked yes)
			(layer "F.Fab")
			(hide yes)
			(effects
				(font
					(size 1.016 1.016)
					(thickness 0.1524)
				)
			)
		)
		(property "Device Type" "C402H22"
			(at 1.1811 -4.2291 0)
			(unlocked yes)
			(layer "F.Fab")
			(hide yes)
			(effects
				(font
					(size 1.016 1.016)
					(thickness 0.1524)
				)
			)
		)
		(duplicate_pad_numbers_are_jumpers no)
		(fp_rect
			(start -0.4318 0.9525)
			(end 0.4318 -0.9525)
			(stroke
				(width 0)
				(type default)
			)
			(fill no)
			(layer "F.CrtYd")
		)
		(fp_rect
			(start -0.4318 0.9525)
			(end 0.4318 -0.9525)
			(stroke
				(width 0)
				(type default)
			)
			(fill no)
			(layer "F.Fab")
		)
		(pad "1" smd custom
			(at 0 -0.4445)
			(size 0.1524 0.1524)
			(layers "F.Cu" "F.Mask" "F.Paste")
			(net "MB0_CM_SENSE_P")
			(options
				(clearance outline)
				(anchor circle)
			)
			(primitives
				(gr_poly
					(pts
						(arc
							(start 0.3048 -0.2032)
							(mid 0.275042 -0.275042)
							(end 0.2032 -0.3048)
						)
						(arc
							(start -0.2032 -0.3048)
							(mid -0.275042 -0.275042)
							(end -0.3048 -0.2032)
						)
						(arc
							(start -0.3048 0.2032)
							(mid -0.275042 0.275042)
							(end -0.2032 0.3048)
						)
						(arc
							(start 0.2032 0.3048)
							(mid 0.275042 0.275042)
							(end 0.3048 0.2032)
						)
					)
					(width 0)
					(fill yes)
				)
			)
		)
		(pad "2" smd custom
			(at 0 0.4445)
			(size 0.1524 0.1524)
			(layers "F.Cu" "F.Mask" "F.Paste")
			(net "MB0_CM_SENSE_N")
			(options
				(clearance outline)
				(anchor circle)
			)
			(primitives
				(gr_poly
					(pts
						(arc
							(start 0.3048 -0.2032)
							(mid 0.275042 -0.275042)
							(end 0.2032 -0.3048)
						)
						(arc
							(start -0.2032 -0.3048)
							(mid -0.275042 -0.275042)
							(end -0.3048 -0.2032)
						)
						(arc
							(start -0.3048 0.2032)
							(mid -0.275042 0.275042)
							(end -0.2032 0.3048)
						)
						(arc
							(start 0.2032 0.3048)
							(mid 0.275042 0.275042)
							(end 0.3048 0.2032)
						)
					)
					(width 0)
					(fill yes)
				)
			)
		)
	)
	(footprint ""
		(layer "F.Cu")
		(at 214.568532 -388.795514 90)
		(property "Reference" "U48"
			(at 0 0 90)
			(layer "F.SilkS")
			(hide yes)
			(effects
				(font
					(size 1.27 1.27)
				)
			)
		)
		(property "Value" "SN74LVC1G08DCKR-GP"
			(at -2.3368 -8.6868 90)
			(unlocked yes)
			(layer "F.Fab")
			(hide yes)
			(effects
				(font
					(size 1.016 1.016)
					(thickness 0.1524)
				)
			)
		)
		(property "Device Type" "SC70-5H44"
			(at -2.3114 -10.414 90)
			(unlocked yes)
			(layer "F.Fab")
			(hide yes)
			(effects
				(font
					(size 1.016 1.016)
					(thickness 0.1524)
				)
			)
		)
		(duplicate_pad_numbers_are_jumpers no)
		(fp_line
			(start 1.3843 -1.8034)
			(end 1.3843 -1.1176)
			(stroke
				(width 0.3302)
				(type default)
			)
			(layer "F.SilkS")
		)
		(fp_line
			(start 0.6604 -1.8034)
			(end 1.3843 -1.8034)
			(stroke
				(width 0.3302)
				(type default)
			)
			(layer "F.SilkS")
		)
		(fp_line
			(start 1.27 -1.7018)
			(end 1.27 1.7018)
			(stroke
				(width 0.1524)
				(type default)
			)
			(layer "F.SilkS")
		)
		(fp_line
			(start -1.27 -1.7018)
			(end 1.27 -1.7018)
			(stroke
				(width 0.1524)
				(type default)
			)
			(layer "F.SilkS")
		)
		(fp_line
			(start 1.27 1.7018)
			(end -1.27 1.7018)
			(stroke
				(width 0.1524)
				(type default)
			)
			(layer "F.SilkS")
		)
		(fp_line
			(start -1.27 1.7018)
			(end -1.27 -1.7018)
			(stroke
				(width 0.1524)
				(type default)
			)
			(layer "F.SilkS")
		)
		(fp_rect
			(start -1.524 1.9558)
			(end 1.524 -1.9558)
			(stroke
				(width 0)
				(type default)
			)
			(fill no)
			(layer "F.CrtYd")
		)
		(fp_poly
			(pts
				(xy -1.524 -1.9558) (xy 1.524 -1.9558) (xy 1.524 1.9558) (xy -1.524 1.9558)
			)
			(stroke
				(width 0)
				(type default)
			)
			(fill no)
			(layer "F.Fab")
		)
		(pad "1" smd rect
			(at 0.65024 -0.8255 90)
			(size 0.4064 1.2192)
			(layers "F.Cu" "F.Mask" "F.Paste")
			(net "BMC_B_TO_EXP_B_RESET_N")
		)
		(pad "2" smd rect
			(at 0 -0.8255 90)
			(size 0.4064 1.2192)
			(layers "F.Cu" "F.Mask" "F.Paste")
			(net "RST_BTN_B_N")
		)
		(pad "3" smd rect
			(at -0.65024 -0.8255 90)
			(size 0.4064 1.2192)
			(layers "F.Cu" "F.Mask" "F.Paste")
			(net "GND")
		)
		(pad "4" smd rect
			(at -0.65024 0.8255 90)
			(size 0.4064 1.2192)
			(layers "F.Cu" "F.Mask" "F.Paste")
			(net "SCC_B_RESET_N")
		)
		(pad "5" smd rect
			(at 0.65024 0.8255 90)
			(size 0.4064 1.2192)
			(layers "F.Cu" "F.Mask" "F.Paste")
			(net "P3V3_STBY_B")
		)
	)
)
